(kicad_pcb
	(version 20260206)
	(generator "pcbnew")
	(generator_version "10.0")
	(general
		(thickness 1.6)
		(legacy_teardrops no)
	)
	(paper "A4")
	(title_block
		(title "peb — Lightning_PEB_BRD.brd")
		(comment 1 "Lightning (Wiwynn / Facebook NVMe JBOF) / footprints 2443-2449 of 2563")
	)
	(layers
		(0 "F.Cu" signal "TOP")
		(4 "In1.Cu" signal "L2GND")
		(6 "In2.Cu" signal "L3")
		(8 "In3.Cu" signal "L4VCC")
		(10 "In4.Cu" signal "L5VCC")
		(12 "In5.Cu" signal "L6")
		(14 "In6.Cu" signal "L7GND")
		(2 "B.Cu" signal "BOTTOM")
		(9 "F.Adhes" user "F.Adhesive")
		(11 "B.Adhes" user "B.Adhesive")
		(13 "F.Paste" user "Package Geometry/Pastemask Top")
		(15 "B.Paste" user "Package Geometry/Pastemask Bottom")
		(5 "F.SilkS" user "Ref Des/Silkscreen Top")
		(7 "B.SilkS" user "Ref Des/Silkscreen Bottom")
		(1 "F.Mask" user "Board Geometry/Soldermask Top")
		(3 "B.Mask" user "Board Geometry/Soldermask Bottom")
		(17 "Dwgs.User" user "User.Drawings")
		(19 "Cmts.User" user "User.Comments")
		(21 "Eco1.User" user "User.Eco1")
		(23 "Eco2.User" user "User.Eco2")
		(25 "Edge.Cuts" user "Board Geometry/Outline")
		(27 "Margin" user)
		(31 "F.CrtYd" user "Package Geometry/Place Bound Top")
		(29 "B.CrtYd" user "Package Geometry/Place Bound Bottom")
		(35 "F.Fab" user "Ref Des/Assembly Top")
		(33 "B.Fab" user "Ref Des/Assembly Bottom")
	)
	(footprint ""
		(layer "B.Cu")
		(at 54.8894 -113.8428 90)
		(property "Reference" "R436"
			(at 0 0 90)
			(layer "B.SilkS")
			(hide yes)
			(effects
				(font
					(size 1.27 1.27)
				)
				(justify mirror)
			)
		)
		(property "Value" "4K7R2F-GP"
			(at -0.064008 -3.993896 90)
			(unlocked yes)
			(layer "B.Fab")
			(hide yes)
			(effects
				(font
					(size 1.016 1.016)
					(thickness 0.1524)
				)
				(justify mirror)
			)
		)
		(property "Device Type" "R402H16"
			(at -0.064008 -5.517896 90)
			(unlocked yes)
			(layer "B.Fab")
			(hide yes)
			(effects
				(font
					(size 1.016 1.016)
					(thickness 0.1524)
				)
				(justify mirror)
			)
		)
		(duplicate_pad_numbers_are_jumpers no)
		(fp_line
			(start 0.508 -0.9398)
			(end 0.508 0.9398)
			(stroke
				(width 0.1524)
				(type default)
			)
			(layer "B.SilkS")
		)
		(fp_line
			(start -0.508 -0.9398)
			(end 0.508 -0.9398)
			(stroke
				(width 0.1524)
				(type default)
			)
			(layer "B.SilkS")
		)
		(fp_rect
			(start 0.508 0.9398)
			(end -0.508 -0.9398)
			(stroke
				(width 0)
				(type default)
			)
			(fill no)
			(layer "B.CrtYd")
		)
		(fp_rect
			(start 0.508 0.9398)
			(end -0.508 -0.9398)
			(stroke
				(width 0)
				(type default)
			)
			(fill no)
			(layer "B.Fab")
		)
		(pad "1" smd custom
			(at 0 -0.4445 270)
			(size 0.1397 0.1397)
			(layers "B.Cu" "B.Mask" "B.Paste")
			(net "BMC_I2C12_MINI6_SDA_S")
			(options
				(clearance outline)
				(anchor circle)
			)
			(primitives
				(gr_poly
					(pts
						(arc
							(start -0.1778 0.2794)
							(mid -0.249642 0.249642)
							(end -0.2794 0.1778)
						)
						(arc
							(start -0.2794 -0.1778)
							(mid -0.249642 -0.249642)
							(end -0.1778 -0.2794)
						)
						(arc
							(start 0.1778 -0.2794)
							(mid 0.249642 -0.249642)
							(end 0.2794 -0.1778)
						)
						(arc
							(start 0.2794 0.1778)
							(mid 0.249642 0.249642)
							(end 0.1778 0.2794)
						)
					)
					(width 0)
					(fill yes)
				)
			)
		)
		(pad "2" smd custom
			(at 0 0.4445 270)
			(size 0.1397 0.1397)
			(layers "B.Cu" "B.Mask" "B.Paste")
			(net "P3V3_STBY")
			(options
				(clearance outline)
				(anchor circle)
			)
			(primitives
				(gr_poly
					(pts
						(arc
							(start -0.1778 0.2794)
							(mid -0.249642 0.249642)
							(end -0.2794 0.1778)
						)
						(arc
							(start -0.2794 -0.1778)
							(mid -0.249642 -0.249642)
							(end -0.1778 -0.2794)
						)
						(arc
							(start 0.1778 -0.2794)
							(mid 0.249642 -0.249642)
							(end 0.2794 -0.1778)
						)
						(arc
							(start 0.2794 0.1778)
							(mid 0.249642 0.249642)
							(end 0.1778 0.2794)
						)
					)
					(width 0)
					(fill yes)
				)
			)
		)
	)
	(footprint ""
		(layer "B.Cu")
		(at 133.326124 -208.889092 180)
		(property "Reference" "R4119"
			(at 0 0 0)
			(layer "B.SilkS")
			(hide yes)
			(effects
				(font
					(size 1.27 1.27)
				)
				(justify mirror)
			)
		)
		(property "Value" "4K7R2F-GP"
			(at -0.064008 -3.993896 180)
			(unlocked yes)
			(layer "B.Fab")
			(hide yes)
			(effects
				(font
					(size 1.016 1.016)
					(thickness 0.1524)
				)
				(justify mirror)
			)
		)
		(property "Device Type" "R402H16"
			(at -0.064008 -5.517896 180)
			(unlocked yes)
			(layer "B.Fab")
			(hide yes)
			(effects
				(font
					(size 1.016 1.016)
					(thickness 0.1524)
				)
				(justify mirror)
			)
		)
		(duplicate_pad_numbers_are_jumpers no)
		(fp_line
			(start 0.508 -0.9398)
			(end 0.508 0.9398)
			(stroke
				(width 0.1524)
				(type default)
			)
			(layer "B.SilkS")
		)
		(fp_line
			(start -0.508 -0.9398)
			(end 0.508 -0.9398)
			(stroke
				(width 0.1524)
				(type default)
			)
			(layer "B.SilkS")
		)
		(fp_rect
			(start 0.508 0.9398)
			(end -0.508 -0.9398)
			(stroke
				(width 0)
				(type default)
			)
			(fill no)
			(layer "B.CrtYd")
		)
		(fp_rect
			(start 0.508 0.9398)
			(end -0.508 -0.9398)
			(stroke
				(width 0)
				(type default)
			)
			(fill no)
			(layer "B.Fab")
		)
		(pad "1" smd custom
			(at 0 -0.4445)
			(size 0.1397 0.1397)
			(layers "B.Cu" "B.Mask" "B.Paste")
			(net "SSD_ATNLED#6")
			(options
				(clearance outline)
				(anchor circle)
			)
			(primitives
				(gr_poly
					(pts
						(arc
							(start -0.1778 0.2794)
							(mid -0.249642 0.249642)
							(end -0.2794 0.1778)
						)
						(arc
							(start -0.2794 -0.1778)
							(mid -0.249642 -0.249642)
							(end -0.1778 -0.2794)
						)
						(arc
							(start 0.1778 -0.2794)
							(mid 0.249642 -0.249642)
							(end 0.2794 -0.1778)
						)
						(arc
							(start 0.2794 0.1778)
							(mid 0.249642 0.249642)
							(end 0.1778 0.2794)
						)
					)
					(width 0)
					(fill yes)
				)
			)
		)
		(pad "2" smd custom
			(at 0 0.4445)
			(size 0.1397 0.1397)
			(layers "B.Cu" "B.Mask" "B.Paste")
			(net "P3V3_STBY")
			(options
				(clearance outline)
				(anchor circle)
			)
			(primitives
				(gr_poly
					(pts
						(arc
							(start -0.1778 0.2794)
							(mid -0.249642 0.249642)
							(end -0.2794 0.1778)
						)
						(arc
							(start -0.2794 -0.1778)
							(mid -0.249642 -0.249642)
							(end -0.1778 -0.2794)
						)
						(arc
							(start 0.1778 -0.2794)
							(mid 0.249642 -0.249642)
							(end 0.2794 -0.1778)
						)
						(arc
							(start 0.2794 0.1778)
							(mid 0.249642 0.249642)
							(end 0.1778 0.2794)
						)
					)
					(width 0)
					(fill yes)
				)
			)
		)
	)
	(footprint ""
		(layer "B.Cu")
		(at 269.580868 -16.940276)
		(property "Reference" "R719"
			(at 0 0 0)
			(layer "B.SilkS")
			(hide yes)
			(effects
				(font
					(size 1.27 1.27)
				)
				(justify mirror)
			)
		)
		(property "Value" "0R2J-2-GP"
			(at -0.064008 -3.993896 0)
			(unlocked yes)
			(layer "B.Fab")
			(hide yes)
			(effects
				(font
					(size 1.016 1.016)
					(thickness 0.1524)
				)
				(justify mirror)
			)
		)
		(property "Device Type" "R402H16"
			(at -0.064008 -5.517896 0)
			(unlocked yes)
			(layer "B.Fab")
			(hide yes)
			(effects
				(font
					(size 1.016 1.016)
					(thickness 0.1524)
				)
				(justify mirror)
			)
		)
		(duplicate_pad_numbers_are_jumpers no)
		(fp_line
			(start -0.508 -0.9398)
			(end 0.508 -0.9398)
			(stroke
				(width 0.1524)
				(type default)
			)
			(layer "B.SilkS")
		)
		(fp_line
			(start 0.508 -0.9398)
			(end 0.508 0.9398)
			(stroke
				(width 0.1524)
				(type default)
			)
			(layer "B.SilkS")
		)
		(fp_rect
			(start 0.508 0.9398)
			(end -0.508 -0.9398)
			(stroke
				(width 0)
				(type default)
			)
			(fill no)
			(layer "B.CrtYd")
		)
		(fp_rect
			(start 0.508 0.9398)
			(end -0.508 -0.9398)
			(stroke
				(width 0)
				(type default)
			)
			(fill no)
			(layer "B.Fab")
		)
		(pad "1" smd custom
			(at 0 -0.4445 180)
			(size 0.1397 0.1397)
			(layers "B.Cu" "B.Mask" "B.Paste")
			(net "8644_USB_DP5")
			(options
				(clearance outline)
				(anchor circle)
			)
			(primitives
				(gr_poly
					(pts
						(arc
							(start -0.1778 0.2794)
							(mid -0.249642 0.249642)
							(end -0.2794 0.1778)
						)
						(arc
							(start -0.2794 -0.1778)
							(mid -0.249642 -0.249642)
							(end -0.1778 -0.2794)
						)
						(arc
							(start 0.1778 -0.2794)
							(mid 0.249642 -0.249642)
							(end 0.2794 -0.1778)
						)
						(arc
							(start 0.2794 0.1778)
							(mid 0.249642 0.249642)
							(end 0.1778 0.2794)
						)
					)
					(width 0)
					(fill yes)
				)
			)
		)
		(pad "2" smd custom
			(at 0 0.4445 180)
			(size 0.1397 0.1397)
			(layers "B.Cu" "B.Mask" "B.Paste")
			(net "P3V3_STBY")
			(options
				(clearance outline)
				(anchor circle)
			)
			(primitives
				(gr_poly
					(pts
						(arc
							(start -0.1778 0.2794)
							(mid -0.249642 0.249642)
							(end -0.2794 0.1778)
						)
						(arc
							(start -0.2794 -0.1778)
							(mid -0.249642 -0.249642)
							(end -0.1778 -0.2794)
						)
						(arc
							(start 0.1778 -0.2794)
							(mid 0.249642 -0.249642)
							(end 0.2794 -0.1778)
						)
						(arc
							(start 0.2794 0.1778)
							(mid 0.249642 0.249642)
							(end 0.1778 0.2794)
						)
					)
					(width 0)
					(fill yes)
				)
			)
		)
	)
	(footprint ""
		(layer "B.Cu")
		(at 349.040196 -45.46473 180)
		(property "Reference" "U47"
			(at 0 0 0)
			(layer "B.SilkS")
			(hide yes)
			(effects
				(font
					(size 1.27 1.27)
				)
				(justify mirror)
			)
		)
		(property "Value" "SN74LVC1G08DCKR-GP"
			(at 2.3368 -8.6868 180)
			(unlocked yes)
			(layer "B.Fab")
			(hide yes)
			(effects
				(font
					(size 1.016 1.016)
					(thickness 0.1524)
				)
				(justify mirror)
			)
		)
		(property "Device Type" "SC70-5H44"
			(at 2.3114 -10.414 180)
			(unlocked yes)
			(layer "B.Fab")
			(hide yes)
			(effects
				(font
					(size 1.016 1.016)
					(thickness 0.1524)
				)
				(justify mirror)
			)
		)
		(duplicate_pad_numbers_are_jumpers no)
		(fp_line
			(start 1.27 1.7018)
			(end 1.27 -1.7018)
			(stroke
				(width 0.1524)
				(type default)
			)
			(layer "B.SilkS")
		)
		(fp_line
			(start 1.27 -1.7018)
			(end -1.27 -1.7018)
			(stroke
				(width 0.1524)
				(type default)
			)
			(layer "B.SilkS")
		)
		(fp_line
			(start -0.6604 -1.8034)
			(end -1.3843 -1.8034)
			(stroke
				(width 0.3302)
				(type default)
			)
			(layer "B.SilkS")
		)
		(fp_line
			(start -1.27 1.7018)
			(end 1.27 1.7018)
			(stroke
				(width 0.1524)
				(type default)
			)
			(layer "B.SilkS")
		)
		(fp_line
			(start -1.27 -1.7018)
			(end -1.27 1.7018)
			(stroke
				(width 0.1524)
				(type default)
			)
			(layer "B.SilkS")
		)
		(fp_line
			(start -1.3843 -1.8034)
			(end -1.3843 -1.1176)
			(stroke
				(width 0.3302)
				(type default)
			)
			(layer "B.SilkS")
		)
		(fp_rect
			(start 1.524 1.9558)
			(end -1.524 -1.9558)
			(stroke
				(width 0)
				(type default)
			)
			(fill no)
			(layer "B.CrtYd")
		)
		(fp_poly
			(pts
				(xy 1.524 -1.9558) (xy -1.524 -1.9558) (xy -1.524 1.9558) (xy 1.524 1.9558)
			)
			(stroke
				(width 0)
				(type default)
			)
			(fill no)
			(layer "B.Fab")
		)
		(pad "1" smd rect
			(at -0.65024 -0.8255)
			(size 0.4064 1.2192)
			(layers "B.Cu" "B.Mask" "B.Paste")
			(net "PE1_PERST#_R")
		)
		(pad "2" smd rect
			(at 0 -0.8255)
			(size 0.4064 1.2192)
			(layers "B.Cu" "B.Mask" "B.Paste")
			(net "PM8536_PG2_R")
		)
		(pad "3" smd rect
			(at 0.65024 -0.8255)
			(size 0.4064 1.2192)
			(layers "B.Cu" "B.Mask" "B.Paste")
			(net "GND")
		)
		(pad "4" smd rect
			(at 0.65024 0.8255)
			(size 0.4064 1.2192)
			(layers "B.Cu" "B.Mask" "B.Paste")
			(net "PM8536_RST#_AND")
		)
		(pad "5" smd rect
			(at -0.65024 0.8255)
			(size 0.4064 1.2192)
			(layers "B.Cu" "B.Mask" "B.Paste")
			(net "P3V3_STBY")
		)
	)
	(footprint ""
		(layer "B.Cu")
		(at 246.59463 -60.071)
		(property "Reference" "C603"
			(at 0 0 0)
			(layer "B.SilkS")
			(hide yes)
			(effects
				(font
					(size 1.27 1.27)
				)
				(justify mirror)
			)
		)
		(property "Value" "SCD1U16V1KX-1-GP"
			(at 2.8321 -1.7399 0)
			(unlocked yes)
			(layer "B.Fab")
			(hide yes)
			(effects
				(font
					(size 1.016 1.016)
					(thickness 0.1524)
				)
				(justify mirror)
			)
		)
		(property "Device Type" "C0201H13"
			(at 2.8321 -3.2639 0)
			(unlocked yes)
			(layer "B.Fab")
			(hide yes)
			(effects
				(font
					(size 1.016 1.016)
					(thickness 0.1524)
				)
				(justify mirror)
			)
		)
		(duplicate_pad_numbers_are_jumpers no)
		(fp_rect
			(start 0.2794 0.6477)
			(end -0.2794 -0.6477)
			(stroke
				(width 0)
				(type default)
			)
			(fill no)
			(layer "B.CrtYd")
		)
		(fp_rect
			(start 0.2794 0.6477)
			(end -0.2794 -0.6477)
			(stroke
				(width 0)
				(type default)
			)
			(fill no)
			(layer "B.Fab")
		)
		(pad "1" smd custom
			(at 0 -0.2794 180)
			(size 0.0762 0.0762)
			(layers "B.Cu" "B.Mask" "B.Paste")
			(net "DUT_AVD_PCIE")
			(options
				(clearance outline)
				(anchor circle)
			)
			(primitives
				(gr_poly
					(pts
						(arc
							(start 0.1524 0.127)
							(mid 0.137521 0.162921)
							(end 0.1016 0.1778)
						)
						(arc
							(start -0.1016 0.1778)
							(mid -0.137521 0.162921)
							(end -0.1524 0.127)
						)
						(arc
							(start -0.1524 -0.127)
							(mid -0.137521 -0.162921)
							(end -0.1016 -0.1778)
						)
						(arc
							(start 0.1016 -0.1778)
							(mid 0.137521 -0.162921)
							(end 0.1524 -0.127)
						)
					)
					(width 0)
					(fill yes)
				)
			)
		)
		(pad "2" smd custom
			(at 0 0.2794 180)
			(size 0.0762 0.0762)
			(layers "B.Cu" "B.Mask" "B.Paste")
			(net "GND")
			(options
				(clearance outline)
				(anchor circle)
			)
			(primitives
				(gr_poly
					(pts
						(arc
							(start 0.1524 0.127)
							(mid 0.137521 0.162921)
							(end 0.1016 0.1778)
						)
						(arc
							(start -0.1016 0.1778)
							(mid -0.137521 0.162921)
							(end -0.1524 0.127)
						)
						(arc
							(start -0.1524 -0.127)
							(mid -0.137521 -0.162921)
							(end -0.1016 -0.1778)
						)
						(arc
							(start 0.1016 -0.1778)
							(mid 0.137521 -0.162921)
							(end 0.1524 -0.127)
						)
					)
					(width 0)
					(fill yes)
				)
			)
		)
	)
	(footprint ""
		(layer "B.Cu")
		(at 53.721 -133.477 -90)
		(property "Reference" "R316"
			(at 0 0 90)
			(layer "B.SilkS")
			(hide yes)
			(effects
				(font
					(size 1.27 1.27)
				)
				(justify mirror)
			)
		)
		(property "Value" "0R2J-2-GP"
			(at -0.064008 -3.993896 270)
			(unlocked yes)
			(layer "B.Fab")
			(hide yes)
			(effects
				(font
					(size 1.016 1.016)
					(thickness 0.1524)
				)
				(justify mirror)
			)
		)
		(property "Device Type" "R402H16"
			(at -0.064008 -5.517896 270)
			(unlocked yes)
			(layer "B.Fab")
			(hide yes)
			(effects
				(font
					(size 1.016 1.016)
					(thickness 0.1524)
				)
				(justify mirror)
			)
		)
		(duplicate_pad_numbers_are_jumpers no)
		(fp_line
			(start -0.508 -0.9398)
			(end 0.508 -0.9398)
			(stroke
				(width 0.1524)
				(type default)
			)
			(layer "B.SilkS")
		)
		(fp_line
			(start 0.508 -0.9398)
			(end 0.508 0.9398)
			(stroke
				(width 0.1524)
				(type default)
			)
			(layer "B.SilkS")
		)
		(fp_rect
			(start 0.508 0.9398)
			(end -0.508 -0.9398)
			(stroke
				(width 0)
				(type default)
			)
			(fill no)
			(layer "B.CrtYd")
		)
		(fp_rect
			(start 0.508 0.9398)
			(end -0.508 -0.9398)
			(stroke
				(width 0)
				(type default)
			)
			(fill no)
			(layer "B.Fab")
		)
		(pad "1" smd custom
			(at 0 -0.4445 90)
			(size 0.1397 0.1397)
			(layers "B.Cu" "B.Mask" "B.Paste")
			(net "ADC_P5V_STBY")
			(options
				(clearance outline)
				(anchor circle)
			)
			(primitives
				(gr_poly
					(pts
						(arc
							(start -0.1778 0.2794)
							(mid -0.249642 0.249642)
							(end -0.2794 0.1778)
						)
						(arc
							(start -0.2794 -0.1778)
							(mid -0.249642 -0.249642)
							(end -0.1778 -0.2794)
						)
						(arc
							(start 0.1778 -0.2794)
							(mid 0.249642 -0.249642)
							(end 0.2794 -0.1778)
						)
						(arc
							(start 0.2794 0.1778)
							(mid 0.249642 0.249642)
							(end 0.1778 0.2794)
						)
					)
					(width 0)
					(fill yes)
				)
			)
		)
		(pad "2" smd custom
			(at 0 0.4445 90)
			(size 0.1397 0.1397)
			(layers "B.Cu" "B.Mask" "B.Paste")
			(net "ADC_P5V_STBY_BMC")
			(options
				(clearance outline)
				(anchor circle)
			)
			(primitives
				(gr_poly
					(pts
						(arc
							(start -0.1778 0.2794)
							(mid -0.249642 0.249642)
							(end -0.2794 0.1778)
						)
						(arc
							(start -0.2794 -0.1778)
							(mid -0.249642 -0.249642)
							(end -0.1778 -0.2794)
						)
						(arc
							(start 0.1778 -0.2794)
							(mid 0.249642 -0.249642)
							(end 0.2794 -0.1778)
						)
						(arc
							(start 0.2794 0.1778)
							(mid 0.249642 0.249642)
							(end 0.1778 0.2794)
						)
					)
					(width 0)
					(fill yes)
				)
			)
		)
	)
	(footprint ""
		(layer "B.Cu")
		(at 310.007 -65.405 180)
		(property "Reference" "PG66"
			(at 0 0 0)
			(layer "B.SilkS")
			(hide yes)
			(effects
				(font
					(size 1.27 1.27)
				)
				(justify mirror)
			)
		)
		(property "Value" "GAP-CLOSE-PWR-3-GP"
			(at -0.0254 -6.5786 180)
			(unlocked yes)
			(layer "B.Fab")
			(hide yes)
			(effects
				(font
					(size 1.016 1.016)
					(thickness 0.1524)
				)
				(justify mirror)
			)
		)
		(property "Device Type" "GAP-CLOSE-PWR-3"
			(at -0.0254 -8.255 180)
			(unlocked yes)
			(layer "B.Fab")
			(hide yes)
			(effects
				(font
					(size 1.016 1.016)
					(thickness 0.1524)
				)
				(justify mirror)
			)
		)
		(duplicate_pad_numbers_are_jumpers no)
		(fp_rect
			(start 0.7112 0.4572)
			(end -0.7112 -0.4572)
			(stroke
				(width 0)
				(type default)
			)
			(fill no)
			(layer "B.CrtYd")
		)
		(fp_poly
			(pts
				(xy 0.7112 -0.4572) (xy -0.7112 -0.4572) (xy -0.7112 0.4572) (xy 0.7112 0.4572)
			)
			(stroke
				(width 0)
				(type default)
			)
			(fill no)
			(layer "B.Fab")
		)
		(pad "1" smd rect
			(at 0.3048 0)
			(size 0.6604 0.762)
			(layers "B.Cu" "B.Mask" "B.Paste")
			(net "DUT_VDD")
		)
		(pad "2" smd rect
			(at -0.3048 0)
			(size 0.6604 0.762)
			(layers "B.Cu" "B.Mask" "B.Paste")
			(net "P0V9_E")
		)
	)
)
